(kicad_pcb
	(version 20260206)
	(generator "pcbnew")
	(generator_version "10.0")
	(general
		(thickness 1.6)
		(legacy_teardrops no)
	)
	(paper "A4")
	(title_block
		(title "Bryce Canyon_R.DPB_16317-1_OCP.brd")
		(comment 1 "Bryce Canyon / footprints 1047-1052 of 2099")
	)
	(layers
		(0 "F.Cu" signal "TOP")
		(4 "In1.Cu" signal "L2GND")
		(6 "In2.Cu" signal "L3")
		(8 "In3.Cu" signal "L4VCC")
		(10 "In4.Cu" signal "L5VCC")
		(12 "In5.Cu" signal "L6")
		(14 "In6.Cu" signal "L7GND")
		(2 "B.Cu" signal "BOTTOM")
		(9 "F.Adhes" user "F.Adhesive")
		(11 "B.Adhes" user "B.Adhesive")
		(13 "F.Paste" user "Package Geometry/Pastemask Top")
		(15 "B.Paste" user "Package Geometry/Pastemask Bottom")
		(5 "F.SilkS" user "Ref Des/Silkscreen Top")
		(7 "B.SilkS" user "Ref Des/Silkscreen Bottom")
		(1 "F.Mask" user "Board Geometry/Soldermask Top")
		(3 "B.Mask" user "Board Geometry/Soldermask Bottom")
		(17 "Dwgs.User" user "User.Drawings")
		(19 "Cmts.User" user "User.Comments")
		(21 "Eco1.User" user "User.Eco1")
		(23 "Eco2.User" user "User.Eco2")
		(25 "Edge.Cuts" user "Board Geometry/Outline")
		(27 "Margin" user)
		(31 "F.CrtYd" user "Package Geometry/Place Bound Top")
		(29 "B.CrtYd" user "Package Geometry/Place Bound Bottom")
		(35 "F.Fab" user "Ref Des/Assembly Top")
		(33 "B.Fab" user "Ref Des/Assembly Bottom")
	)
	(footprint ""
		(layer "F.Cu")
		(at 181.991 -160.401 180)
		(property "Reference" "C256"
			(at 0 0 180)
			(layer "F.SilkS")
			(hide yes)
			(effects
				(font
					(size 1.27 1.27)
				)
			)
		)
		(property "Value" "SC1U25V3KX-GP"
			(at 0 -2.8194 180)
			(unlocked yes)
			(layer "F.Fab")
			(hide yes)
			(effects
				(font
					(size 1.016 1.016)
					(thickness 0.1524)
				)
			)
		)
		(property "Device Type" "C603H36"
			(at 0 -4.3434 180)
			(unlocked yes)
			(layer "F.Fab")
			(hide yes)
			(effects
				(font
					(size 1.016 1.016)
					(thickness 0.1524)
				)
			)
		)
		(duplicate_pad_numbers_are_jumpers no)
		(fp_line
			(start 0.508 0)
			(end -0.508 0)
			(stroke
				(width 0.2032)
				(type default)
			)
			(layer "F.SilkS")
		)
		(fp_rect
			(start -0.5842 1.3335)
			(end 0.5842 -1.3335)
			(stroke
				(width 0)
				(type default)
			)
			(fill no)
			(layer "F.CrtYd")
		)
		(fp_rect
			(start -0.5842 1.3335)
			(end 0.5842 -1.3335)
			(stroke
				(width 0)
				(type default)
			)
			(fill no)
			(layer "F.Fab")
		)
		(pad "1" smd custom
			(at 0 -0.762 180)
			(size 0.2159 0.2159)
			(layers "F.Cu" "F.Mask" "F.Paste")
			(net "P12V_HDD17")
			(options
				(clearance outline)
				(anchor circle)
			)
			(primitives
				(gr_poly
					(pts
						(arc
							(start -0.3302 -0.4318)
							(mid -0.402042 -0.402042)
							(end -0.4318 -0.3302)
						)
						(arc
							(start -0.4318 0.3302)
							(mid -0.402042 0.402042)
							(end -0.3302 0.4318)
						)
						(arc
							(start 0.3302 0.4318)
							(mid 0.402042 0.402042)
							(end 0.4318 0.3302)
						)
						(arc
							(start 0.4318 -0.3302)
							(mid 0.402042 -0.402042)
							(end 0.3302 -0.4318)
						)
					)
					(width 0)
					(fill yes)
				)
			)
		)
		(pad "2" smd custom
			(at 0 0.762 180)
			(size 0.2159 0.2159)
			(layers "F.Cu" "F.Mask" "F.Paste")
			(net "GND")
			(options
				(clearance outline)
				(anchor circle)
			)
			(primitives
				(gr_poly
					(pts
						(arc
							(start -0.3302 -0.4318)
							(mid -0.402042 -0.402042)
							(end -0.4318 -0.3302)
						)
						(arc
							(start -0.4318 0.3302)
							(mid -0.402042 0.402042)
							(end -0.3302 0.4318)
						)
						(arc
							(start 0.3302 0.4318)
							(mid 0.402042 0.402042)
							(end 0.4318 0.3302)
						)
						(arc
							(start 0.4318 -0.3302)
							(mid 0.402042 -0.402042)
							(end 0.3302 -0.4318)
						)
					)
					(width 0)
					(fill yes)
				)
			)
		)
	)
	(footprint ""
		(layer "F.Cu")
		(at 453.837802 -226.57435 -90)
		(property "Reference" "R1151"
			(at 0 0 270)
			(layer "F.SilkS")
			(hide yes)
			(effects
				(font
					(size 1.27 1.27)
				)
			)
		)
		(property "Value" "309KR2F-GP"
			(at 0.064008 -3.993896 270)
			(unlocked yes)
			(layer "F.Fab")
			(hide yes)
			(effects
				(font
					(size 1.016 1.016)
					(thickness 0.1524)
				)
			)
		)
		(property "Device Type" "R402H16"
			(at 0.064008 -5.517896 270)
			(unlocked yes)
			(layer "F.Fab")
			(hide yes)
			(effects
				(font
					(size 1.016 1.016)
					(thickness 0.1524)
				)
			)
		)
		(duplicate_pad_numbers_are_jumpers no)
		(fp_line
			(start -0.508 -0.9398)
			(end -0.508 0.9398)
			(stroke
				(width 0.1524)
				(type default)
			)
			(layer "F.SilkS")
		)
		(fp_line
			(start 0.508 -0.9398)
			(end -0.508 -0.9398)
			(stroke
				(width 0.1524)
				(type default)
			)
			(layer "F.SilkS")
		)
		(fp_rect
			(start -0.508 0.9398)
			(end 0.508 -0.9398)
			(stroke
				(width 0)
				(type default)
			)
			(fill no)
			(layer "F.CrtYd")
		)
		(fp_rect
			(start -0.508 0.9398)
			(end 0.508 -0.9398)
			(stroke
				(width 0)
				(type default)
			)
			(fill no)
			(layer "F.Fab")
		)
		(pad "1" smd custom
			(at 0 -0.4445 270)
			(size 0.1397 0.1397)
			(layers "F.Cu" "F.Mask" "F.Paste")
			(net "P5V_B_3_RF")
			(options
				(clearance outline)
				(anchor circle)
			)
			(primitives
				(gr_poly
					(pts
						(arc
							(start -0.1778 -0.2794)
							(mid -0.249642 -0.249642)
							(end -0.2794 -0.1778)
						)
						(arc
							(start -0.2794 0.1778)
							(mid -0.249642 0.249642)
							(end -0.1778 0.2794)
						)
						(arc
							(start 0.1778 0.2794)
							(mid 0.249642 0.249642)
							(end 0.2794 0.1778)
						)
						(arc
							(start 0.2794 -0.1778)
							(mid 0.249642 -0.249642)
							(end 0.1778 -0.2794)
						)
					)
					(width 0)
					(fill yes)
				)
			)
		)
		(pad "2" smd custom
			(at 0 0.4445 270)
			(size 0.1397 0.1397)
			(layers "F.Cu" "F.Mask" "F.Paste")
			(net "P5V_B_3_VREG")
			(options
				(clearance outline)
				(anchor circle)
			)
			(primitives
				(gr_poly
					(pts
						(arc
							(start -0.1778 -0.2794)
							(mid -0.249642 -0.249642)
							(end -0.2794 -0.1778)
						)
						(arc
							(start -0.2794 0.1778)
							(mid -0.249642 0.249642)
							(end -0.1778 0.2794)
						)
						(arc
							(start 0.1778 0.2794)
							(mid 0.249642 0.249642)
							(end 0.2794 0.1778)
						)
						(arc
							(start 0.2794 -0.1778)
							(mid 0.249642 -0.249642)
							(end 0.1778 -0.2794)
						)
					)
					(width 0)
					(fill yes)
				)
			)
		)
	)
	(footprint ""
		(layer "F.Cu")
		(at 19.37766 -222.048324 90)
		(property "Reference" "C622"
			(at 0 0 90)
			(layer "F.SilkS")
			(hide yes)
			(effects
				(font
					(size 1.27 1.27)
				)
			)
		)
		(property "Value" "SC10U16V5KX-7-GP-U"
			(at -0.0762 -6.1214 90)
			(unlocked yes)
			(layer "F.Fab")
			(hide yes)
			(effects
				(font
					(size 1.016 1.016)
					(thickness 0.1524)
				)
			)
		)
		(property "Device Type" "C805H58"
			(at -0.0762 -8.1534 90)
			(unlocked yes)
			(layer "F.Fab")
			(hide yes)
			(effects
				(font
					(size 1.016 1.016)
					(thickness 0.1524)
				)
			)
		)
		(duplicate_pad_numbers_are_jumpers no)
		(fp_line
			(start 0.635 0)
			(end -0.635 0)
			(stroke
				(width 0.508)
				(type default)
			)
			(layer "F.SilkS")
		)
		(fp_rect
			(start -0.9652 1.778)
			(end 0.9652 -1.778)
			(stroke
				(width 0)
				(type default)
			)
			(fill no)
			(layer "F.CrtYd")
		)
		(fp_poly
			(pts
				(xy -0.9652 -1.778) (xy 0.9652 -1.778) (xy 0.9652 1.778) (xy -0.9652 1.778)
			)
			(stroke
				(width 0)
				(type default)
			)
			(fill no)
			(layer "F.Fab")
		)
		(pad "1" smd rect
			(at 0 -0.9652 90)
			(size 1.397 1.143)
			(layers "F.Cu" "F.Mask" "F.Paste")
			(net "P12V_B_1_VIN_U31")
		)
		(pad "2" smd rect
			(at 0 0.9652 90)
			(size 1.397 1.143)
			(layers "F.Cu" "F.Mask" "F.Paste")
			(net "GND")
		)
	)
	(footprint ""
		(layer "F.Cu")
		(at 247.000522 -364.845346 -90)
		(property "Reference" "C555"
			(at 0 0 270)
			(layer "F.SilkS")
			(hide yes)
			(effects
				(font
					(size 1.27 1.27)
				)
			)
		)
		(property "Value" "SC1U25V3KX-GP"
			(at 0 -2.8194 270)
			(unlocked yes)
			(layer "F.Fab")
			(hide yes)
			(effects
				(font
					(size 1.016 1.016)
					(thickness 0.1524)
				)
			)
		)
		(property "Device Type" "C603H36"
			(at 0 -4.3434 270)
			(unlocked yes)
			(layer "F.Fab")
			(hide yes)
			(effects
				(font
					(size 1.016 1.016)
					(thickness 0.1524)
				)
			)
		)
		(duplicate_pad_numbers_are_jumpers no)
		(fp_line
			(start 0.508 0)
			(end -0.508 0)
			(stroke
				(width 0.2032)
				(type default)
			)
			(layer "F.SilkS")
		)
		(fp_rect
			(start -0.5842 1.3335)
			(end 0.5842 -1.3335)
			(stroke
				(width 0)
				(type default)
			)
			(fill no)
			(layer "F.CrtYd")
		)
		(fp_rect
			(start -0.5842 1.3335)
			(end 0.5842 -1.3335)
			(stroke
				(width 0)
				(type default)
			)
			(fill no)
			(layer "F.Fab")
		)
		(pad "1" smd custom
			(at 0 -0.762 270)
			(size 0.2159 0.2159)
			(layers "F.Cu" "F.Mask" "F.Paste")
			(net "MB3_P12V_HS")
			(options
				(clearance outline)
				(anchor circle)
			)
			(primitives
				(gr_poly
					(pts
						(arc
							(start -0.3302 -0.4318)
							(mid -0.402042 -0.402042)
							(end -0.4318 -0.3302)
						)
						(arc
							(start -0.4318 0.3302)
							(mid -0.402042 0.402042)
							(end -0.3302 0.4318)
						)
						(arc
							(start 0.3302 0.4318)
							(mid 0.402042 0.402042)
							(end 0.4318 0.3302)
						)
						(arc
							(start 0.4318 -0.3302)
							(mid 0.402042 -0.402042)
							(end 0.3302 -0.4318)
						)
					)
					(width 0)
					(fill yes)
				)
			)
		)
		(pad "2" smd custom
			(at 0 0.762 270)
			(size 0.2159 0.2159)
			(layers "F.Cu" "F.Mask" "F.Paste")
			(net "AGND_CURRENT_DPB")
			(options
				(clearance outline)
				(anchor circle)
			)
			(primitives
				(gr_poly
					(pts
						(arc
							(start -0.3302 -0.4318)
							(mid -0.402042 -0.402042)
							(end -0.4318 -0.3302)
						)
						(arc
							(start -0.4318 0.3302)
							(mid -0.402042 0.402042)
							(end -0.3302 0.4318)
						)
						(arc
							(start 0.3302 0.4318)
							(mid 0.402042 0.402042)
							(end 0.4318 0.3302)
						)
						(arc
							(start 0.4318 -0.3302)
							(mid 0.402042 -0.402042)
							(end 0.3302 -0.4318)
						)
					)
					(width 0)
					(fill yes)
				)
			)
		)
	)
	(footprint ""
		(layer "F.Cu")
		(at 208.90738 -235.18622 180)
		(property "Reference" "R36"
			(at 0 0 180)
			(layer "F.SilkS")
			(hide yes)
			(effects
				(font
					(size 1.27 1.27)
				)
			)
		)
		(property "Value" "4K7R2F-GP"
			(at 0.064008 -3.993896 180)
			(unlocked yes)
			(layer "F.Fab")
			(hide yes)
			(effects
				(font
					(size 1.016 1.016)
					(thickness 0.1524)
				)
			)
		)
		(property "Device Type" "R402H16"
			(at 0.064008 -5.517896 180)
			(unlocked yes)
			(layer "F.Fab")
			(hide yes)
			(effects
				(font
					(size 1.016 1.016)
					(thickness 0.1524)
				)
			)
		)
		(duplicate_pad_numbers_are_jumpers no)
		(fp_line
			(start 0.508 -0.9398)
			(end -0.508 -0.9398)
			(stroke
				(width 0.1524)
				(type default)
			)
			(layer "F.SilkS")
		)
		(fp_line
			(start -0.508 -0.9398)
			(end -0.508 0.9398)
			(stroke
				(width 0.1524)
				(type default)
			)
			(layer "F.SilkS")
		)
		(fp_rect
			(start -0.508 0.9398)
			(end 0.508 -0.9398)
			(stroke
				(width 0)
				(type default)
			)
			(fill no)
			(layer "F.CrtYd")
		)
		(fp_rect
			(start -0.508 0.9398)
			(end 0.508 -0.9398)
			(stroke
				(width 0)
				(type default)
			)
			(fill no)
			(layer "F.Fab")
		)
		(pad "1" smd custom
			(at 0 -0.4445 180)
			(size 0.1397 0.1397)
			(layers "F.Cu" "F.Mask" "F.Paste")
			(net "P3V3_STBY_B")
			(options
				(clearance outline)
				(anchor circle)
			)
			(primitives
				(gr_poly
					(pts
						(arc
							(start -0.1778 -0.2794)
							(mid -0.249642 -0.249642)
							(end -0.2794 -0.1778)
						)
						(arc
							(start -0.2794 0.1778)
							(mid -0.249642 0.249642)
							(end -0.1778 0.2794)
						)
						(arc
							(start 0.1778 0.2794)
							(mid 0.249642 0.249642)
							(end 0.2794 0.1778)
						)
						(arc
							(start 0.2794 -0.1778)
							(mid 0.249642 -0.249642)
							(end 0.1778 -0.2794)
						)
					)
					(width 0)
					(fill yes)
				)
			)
		)
		(pad "2" smd custom
			(at 0 0.4445 180)
			(size 0.1397 0.1397)
			(layers "F.Cu" "F.Mask" "F.Paste")
			(net "IO_EXP4_A0")
			(options
				(clearance outline)
				(anchor circle)
			)
			(primitives
				(gr_poly
					(pts
						(arc
							(start -0.1778 -0.2794)
							(mid -0.249642 -0.249642)
							(end -0.2794 -0.1778)
						)
						(arc
							(start -0.2794 0.1778)
							(mid -0.249642 0.249642)
							(end -0.1778 0.2794)
						)
						(arc
							(start 0.1778 0.2794)
							(mid 0.249642 0.249642)
							(end 0.2794 0.1778)
						)
						(arc
							(start 0.2794 -0.1778)
							(mid 0.249642 -0.249642)
							(end 0.1778 -0.2794)
						)
					)
					(width 0)
					(fill yes)
				)
			)
		)
	)
	(footprint ""
		(layer "F.Cu")
		(at 433.737004 -360.299)
		(property "Reference" "R971"
			(at 0 0 0)
			(layer "F.SilkS")
			(hide yes)
			(effects
				(font
					(size 1.27 1.27)
				)
			)
		)
		(property "Value" "4K7R2J-2-GP"
			(at 0.064008 -3.993896 0)
			(unlocked yes)
			(layer "F.Fab")
			(hide yes)
			(effects
				(font
					(size 1.016 1.016)
					(thickness 0.1524)
				)
			)
		)
		(property "Device Type" "R402H16"
			(at 0.064008 -5.517896 0)
			(unlocked yes)
			(layer "F.Fab")
			(hide yes)
			(effects
				(font
					(size 1.016 1.016)
					(thickness 0.1524)
				)
			)
		)
		(duplicate_pad_numbers_are_jumpers no)
		(fp_line
			(start -0.508 -0.9398)
			(end -0.508 0.9398)
			(stroke
				(width 0.1524)
				(type default)
			)
			(layer "F.SilkS")
		)
		(fp_line
			(start 0.508 -0.9398)
			(end -0.508 -0.9398)
			(stroke
				(width 0.1524)
				(type default)
			)
			(layer "F.SilkS")
		)
		(fp_rect
			(start -0.508 0.9398)
			(end 0.508 -0.9398)
			(stroke
				(width 0)
				(type default)
			)
			(fill no)
			(layer "F.CrtYd")
		)
		(fp_rect
			(start -0.508 0.9398)
			(end 0.508 -0.9398)
			(stroke
				(width 0)
				(type default)
			)
			(fill no)
			(layer "F.Fab")
		)
		(pad "1" smd custom
			(at 0 -0.4445)
			(size 0.1397 0.1397)
			(layers "F.Cu" "F.Mask" "F.Paste")
			(net "P12V_IN")
			(options
				(clearance outline)
				(anchor circle)
			)
			(primitives
				(gr_poly
					(pts
						(arc
							(start -0.1778 -0.2794)
							(mid -0.249642 -0.249642)
							(end -0.2794 -0.1778)
						)
						(arc
							(start -0.2794 0.1778)
							(mid -0.249642 0.249642)
							(end -0.1778 0.2794)
						)
						(arc
							(start 0.1778 0.2794)
							(mid 0.249642 0.249642)
							(end 0.2794 0.1778)
						)
						(arc
							(start 0.2794 -0.1778)
							(mid 0.249642 -0.249642)
							(end 0.1778 -0.2794)
						)
					)
					(width 0)
					(fill yes)
				)
			)
		)
		(pad "2" smd custom
			(at 0 0.4445)
			(size 0.1397 0.1397)
			(layers "F.Cu" "F.Mask" "F.Paste")
			(net "GATE_FAN3")
			(options
				(clearance outline)
				(anchor circle)
			)
			(primitives
				(gr_poly
					(pts
						(arc
							(start -0.1778 -0.2794)
							(mid -0.249642 -0.249642)
							(end -0.2794 -0.1778)
						)
						(arc
							(start -0.2794 0.1778)
							(mid -0.249642 0.249642)
							(end -0.1778 0.2794)
						)
						(arc
							(start 0.1778 0.2794)
							(mid 0.249642 0.249642)
							(end 0.2794 0.1778)
						)
						(arc
							(start 0.2794 -0.1778)
							(mid 0.249642 -0.249642)
							(end 0.1778 -0.2794)
						)
					)
					(width 0)
					(fill yes)
				)
			)
		)
	)
)
